(kicad_pcb
	(version 20260206)
	(generator "pcbnew")
	(generator_version "10.0")
	(general
		(thickness 1.6)
		(legacy_teardrops no)
	)
	(paper "A4")
	(title_block
		(title "Wiwynn_Tioga_Pass_MB.brd")
		(comment 1 "Tioga Pass / footprints 1737-1743 of 4770")
	)
	(layers
		(0 "F.Cu" signal "TOP")
		(4 "In1.Cu" signal "L2GND")
		(6 "In2.Cu" signal "L3")
		(8 "In3.Cu" signal "L4GND")
		(10 "In4.Cu" signal "L5")
		(12 "In5.Cu" signal "L6GND")
		(14 "In6.Cu" signal "L7VCC")
		(16 "In7.Cu" signal "L8VCC")
		(18 "In8.Cu" signal "L9GND")
		(20 "In9.Cu" signal "L10")
		(22 "In10.Cu" signal "L11GND")
		(24 "In11.Cu" signal "L12")
		(26 "In12.Cu" signal "L13GND")
		(2 "B.Cu" signal "BOTTOM")
		(9 "F.Adhes" user "F.Adhesive")
		(11 "B.Adhes" user "B.Adhesive")
		(13 "F.Paste" user "Package Geometry/Pastemask Top")
		(15 "B.Paste" user "Package Geometry/Pastemask Bottom")
		(5 "F.SilkS" user "Ref Des/Silkscreen Top")
		(7 "B.SilkS" user "Ref Des/Silkscreen Bottom")
		(1 "F.Mask" user "Board Geometry/Soldermask Top")
		(3 "B.Mask" user "Board Geometry/Soldermask Bottom")
		(17 "Dwgs.User" user "User.Drawings")
		(19 "Cmts.User" user "User.Comments")
		(21 "Eco1.User" user "User.Eco1")
		(23 "Eco2.User" user "User.Eco2")
		(25 "Edge.Cuts" user "Board Geometry/Outline")
		(27 "Margin" user)
		(31 "F.CrtYd" user "Package Geometry/Place Bound Top")
		(29 "B.CrtYd" user "Package Geometry/Place Bound Bottom")
		(35 "F.Fab" user "Ref Des/Assembly Top")
		(33 "B.Fab" user "Ref Des/Assembly Bottom")
	)
	(footprint ""
		(layer "F.Cu")
		(at 165.608 -6.477 90)
		(property "Reference" "R4G16"
			(at 0 0 90)
			(layer "F.SilkS")
			(hide yes)
			(effects
				(font
					(size 1.27 1.27)
				)
			)
		)
		(property "Value" ""
			(at 0 0 90)
			(layer "F.Fab")
			(effects
				(font
					(size 1.27 1.27)
				)
			)
		)
		(duplicate_pad_numbers_are_jumpers no)
		(fp_poly
			(pts
				(xy -0.2794 -0.1016) (xy 0.2794 -0.1016) (xy 0.2794 0.9906) (xy -0.2794 0.9906)
			)
			(stroke
				(width 0)
				(type default)
			)
			(fill no)
			(layer "F.CrtYd")
		)
		(fp_line
			(start 0.2794 -0.1016)
			(end -0.2794 -0.1016)
			(stroke
				(width 0.1)
				(type default)
			)
			(layer "F.Fab")
		)
		(fp_line
			(start -0.2794 -0.1016)
			(end -0.2794 0.9906)
			(stroke
				(width 0.1)
				(type default)
			)
			(layer "F.Fab")
		)
		(fp_line
			(start 0.2794 0.9906)
			(end 0.2794 -0.1016)
			(stroke
				(width 0.1)
				(type default)
			)
			(layer "F.Fab")
		)
		(fp_line
			(start -0.2794 0.9906)
			(end 0.2794 0.9906)
			(stroke
				(width 0.1)
				(type default)
			)
			(layer "F.Fab")
		)
		(pad "1" smd rect
			(at 0 0 90)
			(size 0.508 0.508)
			(layers "F.Cu" "F.Mask" "F.Paste")
			(net "PWRGD_PVDDQ_GHJ_R")
		)
		(pad "2" smd rect
			(at 0 0.889 90)
			(size 0.508 0.508)
			(layers "F.Cu" "F.Mask" "F.Paste")
			(net "FM_PVTT_GHJ_EN_R")
		)
		(zone
			(layer "F.Cu")
			(hatch none 0.5)
			(connect_pads
				(clearance 0)
			)
			(min_thickness 0.25)
			(keepout
				(tracks allowed)
				(vias not_allowed)
				(pads allowed)
				(copperpour not_allowed)
				(footprints allowed)
			)
			(placement
				(enabled no)
				(sheetname "")
			)
			(fill
				(thermal_gap 0.5)
				(thermal_bridge_width 0.5)
				(island_removal_mode 0)
			)
			(polygon
				(pts
					(xy 165.862 -6.223) (xy 165.862 -6.731) (xy 166.243 -6.731) (xy 166.243 -6.223)
				)
			)
		)
		(zone
			(layer "F.Cu")
			(hatch none 0.5)
			(connect_pads
				(clearance 0)
			)
			(min_thickness 0.25)
			(keepout
				(tracks not_allowed)
				(vias allowed)
				(pads allowed)
				(copperpour not_allowed)
				(footprints allowed)
			)
			(placement
				(enabled no)
				(sheetname "")
			)
			(fill
				(thermal_gap 0.5)
				(thermal_bridge_width 0.5)
				(island_removal_mode 0)
			)
			(polygon
				(pts
					(xy 166.243 -6.223) (xy 166.243 -6.731) (xy 165.862 -6.731) (xy 165.862 -6.223)
				)
			)
		)
	)
	(footprint ""
		(layer "F.Cu")
		(at 117.410484 12.014454 -90)
		(property "Reference" "T1P7"
			(at 0 0 270)
			(layer "F.SilkS")
			(hide yes)
			(effects
				(font
					(size 1.27 1.27)
				)
			)
		)
		(property "Value" "*"
			(at -3.302 1.12395 270)
			(unlocked yes)
			(layer "F.Fab")
			(hide yes)
			(effects
				(font
					(size 0.889 0.889)
					(thickness 0.1524)
				)
			)
		)
		(property "Device Type" "TPAD-DIFF-4P-GP_DISCRET-GB3-TPA"
			(at -3.302 -0.40005 270)
			(unlocked yes)
			(layer "F.Fab")
			(hide yes)
			(effects
				(font
					(size 0.889 0.889)
					(thickness 0.1524)
				)
			)
		)
		(duplicate_pad_numbers_are_jumpers no)
		(fp_line
			(start -2.286 2.286)
			(end 2.286 2.286)
			(stroke
				(width 0.1524)
				(type default)
			)
			(layer "F.SilkS")
		)
		(fp_line
			(start 2.286 2.286)
			(end 2.286 -2.286)
			(stroke
				(width 0.1524)
				(type default)
			)
			(layer "F.SilkS")
		)
		(fp_line
			(start -2.286 -2.286)
			(end -2.286 2.286)
			(stroke
				(width 0.1524)
				(type default)
			)
			(layer "F.SilkS")
		)
		(fp_line
			(start 2.286 -2.286)
			(end -2.286 -2.286)
			(stroke
				(width 0.1524)
				(type default)
			)
			(layer "F.SilkS")
		)
		(fp_line
			(start -2.413 -2.413)
			(end -2.413 -1.143)
			(stroke
				(width 0.4064)
				(type default)
			)
			(layer "F.SilkS")
		)
		(fp_line
			(start -1.143 -2.413)
			(end -2.413 -2.413)
			(stroke
				(width 0.4064)
				(type default)
			)
			(layer "F.SilkS")
		)
		(fp_rect
			(start -2.54 2.54)
			(end 2.54 -2.54)
			(stroke
				(width 0)
				(type default)
			)
			(fill no)
			(layer "F.CrtYd")
		)
		(fp_rect
			(start -2.54 2.54)
			(end 2.54 -2.54)
			(stroke
				(width 0)
				(type default)
			)
			(fill no)
			(layer "F.Fab")
		)
		(pad "1" thru_hole circle
			(at -1.27 -1.27 270)
			(size 1.524 1.524)
			(drill 0.9144)
			(layers "*.Cu" "*.Mask")
			(remove_unused_layers no)
			(net "L1_73OHM_6INCH_DP")
			(clearance -0.0508)
			(thermal_gap 0.127)
			(padstack
				(mode front_inner_back)
				(layer "Inner"
					(shape circle)
					(size 1.1684 1.1684)
					(clearance 0.127)
				)
				(layer "B.Cu"
					(shape circle)
					(size 1.524 1.524)
					(clearance -0.0508)
				)
			)
		)
		(pad "2" thru_hole circle
			(at 1.27 -1.27 270)
			(size 1.524 1.524)
			(drill 0.9144)
			(layers "*.Cu" "*.Mask")
			(remove_unused_layers no)
			(net "L1_73OHM_6INCH_DN")
			(clearance -0.0508)
			(thermal_gap 0.127)
			(padstack
				(mode front_inner_back)
				(layer "Inner"
					(shape circle)
					(size 1.1684 1.1684)
					(clearance 0.127)
				)
				(layer "B.Cu"
					(shape circle)
					(size 1.524 1.524)
					(clearance -0.0508)
				)
			)
		)
		(pad "GND1" thru_hole rect
			(at -1.27 1.27 270)
			(size 1.524 1.524)
			(drill 0.9144)
			(layers "*.Cu" "*.Mask")
			(remove_unused_layers no)
			(net "GND")
			(clearance -0.0508)
			(thermal_gap 0.127)
			(padstack
				(mode front_inner_back)
				(layer "Inner"
					(shape circle)
					(size 1.1684 1.1684)
					(clearance 0.127)
				)
				(layer "B.Cu"
					(shape rect)
					(size 1.524 1.524)
					(clearance -0.0508)
				)
			)
		)
		(pad "GND2" thru_hole rect
			(at 1.27 1.27 270)
			(size 1.524 1.524)
			(drill 0.9144)
			(layers "*.Cu" "*.Mask")
			(remove_unused_layers no)
			(net "GND")
			(clearance -0.0508)
			(thermal_gap 0.127)
			(padstack
				(mode front_inner_back)
				(layer "Inner"
					(shape circle)
					(size 1.1684 1.1684)
					(clearance 0.127)
				)
				(layer "B.Cu"
					(shape rect)
					(size 1.524 1.524)
					(clearance -0.0508)
				)
			)
		)
	)
	(footprint ""
		(layer "F.Cu")
		(at 489.2294 -149.8854 90)
		(property "Reference" "R6W40"
			(at -0.8382 -0.67818 90)
			(unlocked yes)
			(layer "F.SilkS")
			(effects
				(font
					(size 0.4064 0.254)
					(thickness 0.1524)
				)
				(justify left)
			)
		)
		(property "Value" ""
			(at 0 0 90)
			(layer "F.Fab")
			(effects
				(font
					(size 1.27 1.27)
				)
			)
		)
		(duplicate_pad_numbers_are_jumpers no)
		(fp_poly
			(pts
				(xy -0.2794 -0.1016) (xy 0.2794 -0.1016) (xy 0.2794 0.9906) (xy -0.2794 0.9906)
			)
			(stroke
				(width 0)
				(type default)
			)
			(fill no)
			(layer "F.CrtYd")
		)
		(fp_line
			(start 0.2794 -0.1016)
			(end -0.2794 -0.1016)
			(stroke
				(width 0.1)
				(type default)
			)
			(layer "F.Fab")
		)
		(fp_line
			(start -0.2794 -0.1016)
			(end -0.2794 0.9906)
			(stroke
				(width 0.1)
				(type default)
			)
			(layer "F.Fab")
		)
		(fp_line
			(start 0.2794 0.9906)
			(end 0.2794 -0.1016)
			(stroke
				(width 0.1)
				(type default)
			)
			(layer "F.Fab")
		)
		(fp_line
			(start -0.2794 0.9906)
			(end 0.2794 0.9906)
			(stroke
				(width 0.1)
				(type default)
			)
			(layer "F.Fab")
		)
		(pad "1" smd rect
			(at 0 0 90)
			(size 0.508 0.508)
			(layers "F.Cu" "F.Mask" "F.Paste")
			(net "P3V3_STBY")
		)
		(pad "2" smd rect
			(at 0 0.889 90)
			(size 0.508 0.508)
			(layers "F.Cu" "F.Mask" "F.Paste")
			(net "SPA_5V_SIN_SW_D")
		)
		(zone
			(layer "F.Cu")
			(hatch none 0.5)
			(connect_pads
				(clearance 0)
			)
			(min_thickness 0.25)
			(keepout
				(tracks allowed)
				(vias not_allowed)
				(pads allowed)
				(copperpour not_allowed)
				(footprints allowed)
			)
			(placement
				(enabled no)
				(sheetname "")
			)
			(fill
				(thermal_gap 0.5)
				(thermal_bridge_width 0.5)
				(island_removal_mode 0)
			)
			(polygon
				(pts
					(xy 489.4834 -149.6314) (xy 489.4834 -150.1394) (xy 489.8644 -150.1394) (xy 489.8644 -149.6314)
				)
			)
		)
		(zone
			(layer "F.Cu")
			(hatch none 0.5)
			(connect_pads
				(clearance 0)
			)
			(min_thickness 0.25)
			(keepout
				(tracks not_allowed)
				(vias allowed)
				(pads allowed)
				(copperpour not_allowed)
				(footprints allowed)
			)
			(placement
				(enabled no)
				(sheetname "")
			)
			(fill
				(thermal_gap 0.5)
				(thermal_bridge_width 0.5)
				(island_removal_mode 0)
			)
			(polygon
				(pts
					(xy 489.8644 -149.6314) (xy 489.8644 -150.1394) (xy 489.4834 -150.1394) (xy 489.4834 -149.6314)
				)
			)
		)
	)
	(footprint ""
		(layer "F.Cu")
		(at 173.5074 -133.604 -90)
		(property "Reference" "R4B13"
			(at 1.01473 0.656336 180)
			(unlocked yes)
			(layer "F.SilkS")
			(effects
				(font
					(size 0.4064 0.254)
					(thickness 0.1524)
				)
			)
		)
		(property "Value" ""
			(at 0 0 270)
			(layer "F.Fab")
			(effects
				(font
					(size 1.27 1.27)
				)
			)
		)
		(duplicate_pad_numbers_are_jumpers no)
		(fp_poly
			(pts
				(xy -0.4953 -0.2032) (xy 0.4953 -0.2032) (xy 0.4953 1.6002) (xy -0.4953 1.6002)
			)
			(stroke
				(width 0)
				(type default)
			)
			(fill no)
			(layer "F.CrtYd")
		)
		(fp_line
			(start -0.4953 1.6002)
			(end -0.4953 -0.2032)
			(stroke
				(width 0.1)
				(type default)
			)
			(layer "F.Fab")
		)
		(fp_line
			(start 0.4953 1.6002)
			(end -0.4953 1.6002)
			(stroke
				(width 0.1)
				(type default)
			)
			(layer "F.Fab")
		)
		(fp_line
			(start -0.4953 -0.2032)
			(end 0.4953 -0.2032)
			(stroke
				(width 0.1)
				(type default)
			)
			(layer "F.Fab")
		)
		(fp_line
			(start 0.4953 -0.2032)
			(end 0.4953 1.6002)
			(stroke
				(width 0.1)
				(type default)
			)
			(layer "F.Fab")
		)
		(pad "1" smd rect
			(at 0 0 270)
			(size 0.762 0.889)
			(layers "F.Cu" "F.Mask" "F.Paste")
			(net "VR_PVPP_KLM_BOOT")
		)
		(pad "2" smd rect
			(at 0 1.397 270)
			(size 0.762 0.889)
			(layers "F.Cu" "F.Mask" "F.Paste")
			(net "VR_PVPP_KLM_BOOT_R")
		)
		(zone
			(layer "F.Cu")
			(hatch none 0.5)
			(connect_pads
				(clearance 0)
			)
			(min_thickness 0.25)
			(keepout
				(tracks not_allowed)
				(vias allowed)
				(pads allowed)
				(copperpour not_allowed)
				(footprints allowed)
			)
			(placement
				(enabled no)
				(sheetname "")
			)
			(fill
				(thermal_gap 0.5)
				(thermal_bridge_width 0.5)
				(island_removal_mode 0)
			)
			(polygon
				(pts
					(xy 172.5549 -133.985) (xy 172.5549 -133.223) (xy 173.0629 -133.223) (xy 173.0629 -133.985)
				)
			)
		)
		(zone
			(layer "F.Cu")
			(hatch none 0.5)
			(connect_pads
				(clearance 0)
			)
			(min_thickness 0.25)
			(keepout
				(tracks allowed)
				(vias not_allowed)
				(pads allowed)
				(copperpour not_allowed)
				(footprints allowed)
			)
			(placement
				(enabled no)
				(sheetname "")
			)
			(fill
				(thermal_gap 0.5)
				(thermal_bridge_width 0.5)
				(island_removal_mode 0)
			)
			(polygon
				(pts
					(xy 172.5549 -133.223) (xy 173.0629 -133.223) (xy 173.0629 -133.985) (xy 172.5549 -133.985)
				)
			)
		)
	)
	(footprint ""
		(layer "F.Cu")
		(at 379.2982 -30.629352 -90)
		(property "Reference" "R8F21"
			(at 0 0 270)
			(layer "F.SilkS")
			(hide yes)
			(effects
				(font
					(size 1.27 1.27)
				)
			)
		)
		(property "Value" ""
			(at 0 0 270)
			(layer "F.Fab")
			(effects
				(font
					(size 1.27 1.27)
				)
			)
		)
		(duplicate_pad_numbers_are_jumpers no)
		(fp_poly
			(pts
				(xy -0.2794 -0.1016) (xy 0.2794 -0.1016) (xy 0.2794 0.9906) (xy -0.2794 0.9906)
			)
			(stroke
				(width 0)
				(type default)
			)
			(fill no)
			(layer "F.CrtYd")
		)
		(fp_line
			(start -0.2794 0.9906)
			(end 0.2794 0.9906)
			(stroke
				(width 0.1)
				(type default)
			)
			(layer "F.Fab")
		)
		(fp_line
			(start 0.2794 0.9906)
			(end 0.2794 -0.1016)
			(stroke
				(width 0.1)
				(type default)
			)
			(layer "F.Fab")
		)
		(fp_line
			(start -0.2794 -0.1016)
			(end -0.2794 0.9906)
			(stroke
				(width 0.1)
				(type default)
			)
			(layer "F.Fab")
		)
		(fp_line
			(start 0.2794 -0.1016)
			(end -0.2794 -0.1016)
			(stroke
				(width 0.1)
				(type default)
			)
			(layer "F.Fab")
		)
		(pad "1" smd rect
			(at 0 0 270)
			(size 0.508 0.508)
			(layers "F.Cu" "F.Mask" "F.Paste")
			(net "P3E_PCH_RX_0_DN")
		)
		(pad "2" smd rect
			(at 0 0.889 270)
			(size 0.508 0.508)
			(layers "F.Cu" "F.Mask" "F.Paste")
			(net "P3E_PCH_M2_SATA6G_RX_R_DN")
		)
		(zone
			(layer "F.Cu")
			(hatch none 0.5)
			(connect_pads
				(clearance 0)
			)
			(min_thickness 0.25)
			(keepout
				(tracks not_allowed)
				(vias allowed)
				(pads allowed)
				(copperpour not_allowed)
				(footprints allowed)
			)
			(placement
				(enabled no)
				(sheetname "")
			)
			(fill
				(thermal_gap 0.5)
				(thermal_bridge_width 0.5)
				(island_removal_mode 0)
			)
			(polygon
				(pts
					(xy 378.6632 -30.883352) (xy 378.6632 -30.375352) (xy 379.0442 -30.375352) (xy 379.0442 -30.883352)
				)
			)
		)
		(zone
			(layer "F.Cu")
			(hatch none 0.5)
			(connect_pads
				(clearance 0)
			)
			(min_thickness 0.25)
			(keepout
				(tracks allowed)
				(vias not_allowed)
				(pads allowed)
				(copperpour not_allowed)
				(footprints allowed)
			)
			(placement
				(enabled no)
				(sheetname "")
			)
			(fill
				(thermal_gap 0.5)
				(thermal_bridge_width 0.5)
				(island_removal_mode 0)
			)
			(polygon
				(pts
					(xy 379.0442 -30.883352) (xy 379.0442 -30.375352) (xy 378.6632 -30.375352) (xy 378.6632 -30.883352)
				)
			)
		)
	)
	(footprint ""
		(layer "F.Cu")
		(at 176.0855 -132.334 90)
		(property "Reference" "C4B4"
			(at 0 0 90)
			(layer "F.SilkS")
			(hide yes)
			(effects
				(font
					(size 1.27 1.27)
				)
			)
		)
		(property "Value" ""
			(at 0 0 90)
			(layer "F.Fab")
			(effects
				(font
					(size 1.27 1.27)
				)
			)
		)
		(duplicate_pad_numbers_are_jumpers no)
		(fp_poly
			(pts
				(xy 0.3048 -0.1016) (xy 0.3048 0.9906) (xy -0.3048 0.9906) (xy -0.3048 -0.1016)
			)
			(stroke
				(width 0)
				(type default)
			)
			(fill no)
			(layer "F.CrtYd")
		)
		(fp_line
			(start 0.3048 -0.1016)
			(end -0.3048 -0.1016)
			(stroke
				(width 0.1)
				(type default)
			)
			(layer "F.Fab")
		)
		(fp_line
			(start -0.3048 -0.1016)
			(end -0.3048 0.9906)
			(stroke
				(width 0.1)
				(type default)
			)
			(layer "F.Fab")
		)
		(fp_line
			(start 0.3048 0.9906)
			(end 0.3048 -0.1016)
			(stroke
				(width 0.1)
				(type default)
			)
			(layer "F.Fab")
		)
		(fp_line
			(start -0.3048 0.9906)
			(end 0.3048 0.9906)
			(stroke
				(width 0.1)
				(type default)
			)
			(layer "F.Fab")
		)
		(pad "1" smd rect
			(at 0 0 90)
			(size 0.508 0.508)
			(layers "F.Cu" "F.Mask" "F.Paste")
			(net "VR_FB_PVPP_KLM")
		)
		(pad "2" smd rect
			(at 0 0.889 90)
			(size 0.508 0.508)
			(layers "F.Cu" "F.Mask" "F.Paste")
			(net "VR_COMP_PVPP_KLM_3")
		)
		(zone
			(layer "F.Cu")
			(hatch none 0.5)
			(connect_pads
				(clearance 0)
			)
			(min_thickness 0.25)
			(keepout
				(tracks allowed)
				(vias not_allowed)
				(pads allowed)
				(copperpour not_allowed)
				(footprints allowed)
			)
			(placement
				(enabled no)
				(sheetname "")
			)
			(fill
				(thermal_gap 0.5)
				(thermal_bridge_width 0.5)
				(island_removal_mode 0)
			)
			(polygon
				(pts
					(xy 176.3395 -132.08) (xy 176.3395 -132.588) (xy 176.7205 -132.588) (xy 176.7205 -132.08)
				)
			)
		)
		(zone
			(layer "F.Cu")
			(hatch none 0.5)
			(connect_pads
				(clearance 0)
			)
			(min_thickness 0.25)
			(keepout
				(tracks not_allowed)
				(vias allowed)
				(pads allowed)
				(copperpour not_allowed)
				(footprints allowed)
			)
			(placement
				(enabled no)
				(sheetname "")
			)
			(fill
				(thermal_gap 0.5)
				(thermal_bridge_width 0.5)
				(island_removal_mode 0)
			)
			(polygon
				(pts
					(xy 176.7205 -132.08) (xy 176.7205 -132.588) (xy 176.3395 -132.588) (xy 176.3395 -132.08)
				)
			)
		)
	)
	(footprint ""
		(layer "F.Cu")
		(at 114.671602 -77.382116)
		(property "Reference" "C3D16"
			(at 0 0 0)
			(layer "F.SilkS")
			(hide yes)
			(effects
				(font
					(size 1.27 1.27)
				)
			)
		)
		(property "Value" ""
			(at 0 0 0)
			(layer "F.Fab")
			(effects
				(font
					(size 1.27 1.27)
				)
			)
		)
		(duplicate_pad_numbers_are_jumpers no)
		(fp_poly
			(pts
				(xy -0.4953 -0.2032) (xy 0.4953 -0.2032) (xy 0.4953 1.6002) (xy -0.4953 1.6002)
			)
			(stroke
				(width 0)
				(type default)
			)
			(fill no)
			(layer "F.CrtYd")
		)
		(fp_line
			(start -0.4953 -0.2032)
			(end 0.4953 -0.2032)
			(stroke
				(width 0.1)
				(type default)
			)
			(layer "F.Fab")
		)
		(fp_line
			(start -0.4953 1.6002)
			(end -0.4953 -0.2032)
			(stroke
				(width 0.1)
				(type default)
			)
			(layer "F.Fab")
		)
		(fp_line
			(start 0.4953 -0.2032)
			(end 0.4953 1.6002)
			(stroke
				(width 0.1)
				(type default)
			)
			(layer "F.Fab")
		)
		(fp_line
			(start 0.4953 1.6002)
			(end -0.4953 1.6002)
			(stroke
				(width 0.1)
				(type default)
			)
			(layer "F.Fab")
		)
		(pad "1" smd rect
			(at 0 0)
			(size 0.762 0.889)
			(layers "F.Cu" "F.Mask" "F.Paste")
			(net "PVCCIO_CPU1")
		)
		(pad "2" smd rect
			(at 0 1.397)
			(size 0.762 0.889)
			(layers "F.Cu" "F.Mask" "F.Paste")
			(net "GND")
		)
		(zone
			(layer "F.Cu")
			(hatch none 0.5)
			(connect_pads
				(clearance 0)
			)
			(min_thickness 0.25)
			(keepout
				(tracks not_allowed)
				(vias allowed)
				(pads allowed)
				(copperpour not_allowed)
				(footprints allowed)
			)
			(placement
				(enabled no)
				(sheetname "")
			)
			(fill
				(thermal_gap 0.5)
				(thermal_bridge_width 0.5)
				(island_removal_mode 0)
			)
			(polygon
				(pts
					(xy 114.290602 -76.937616) (xy 115.052602 -76.937616) (xy 115.052602 -76.429616) (xy 114.290602 -76.429616)
				)
			)
		)
	)
)
